# TIMECARD (Time Appliance Project (Time Card)) — schematic netlist excerpt (pin names and nets, part order shuffled) for the footprints in the layout excerpt that follows; sources: Cadence DE-HDL packaged netlist, KiCad conversion of R4006-B0001-02_R01.brd

C110  CAPACITOR  0.1UF 10V 10%  pkg SMC_0402R_H022  page 14 : \1\ = FPGA_MGTAVTT ; \2\ = SG
R343  RESISTOR  0OHM -  pkg SMC_0402R_H016  page 19 : \1\ = UNNAMED_8_ICP10100LGA10_I24_RES ; \2\ = SG

(kicad_pcb
	(version 20260206)
	(generator "pcbnew")
	(generator_version "10.0")
	(general
		(thickness 1.6)
		(legacy_teardrops no)
	)
	(paper "A4")
	(title_block
		(title "timecard-production-celestica-r4006 — R4006-B0001-02_R01.brd")
		(comment 1 "Time Appliance Project (Time Card) / footprints 775-776 of 1113")
	)
	(layers
		(0 "F.Cu" signal "TOP")
		(4 "In1.Cu" signal "L02_GND1")
		(6 "In2.Cu" signal "L03_SIG1")
		(8 "In3.Cu" signal "L04_GND2")
		(10 "In4.Cu" signal "L05_VCC1")
		(12 "In5.Cu" signal "L06_VCC2")
		(14 "In6.Cu" signal "L07_GND3")
		(16 "In7.Cu" signal "L08_SIG2")
		(18 "In8.Cu" signal "L09_GND4")
		(2 "B.Cu" signal "BOTTOM")
		(9 "F.Adhes" user "F.Adhesive")
		(11 "B.Adhes" user "B.Adhesive")
		(13 "F.Paste" user "Package Geometry/Pastemask Top")
		(15 "B.Paste" user "Package Geometry/Pastemask Bottom")
		(5 "F.SilkS" user "Ref Des/Silkscreen Top")
		(7 "B.SilkS" user "Ref Des/Silkscreen Bottom")
		(1 "F.Mask" user "Board Geometry/Soldermask Top")
		(3 "B.Mask" user "Board Geometry/Soldermask Bottom")
		(17 "Dwgs.User" user "User.Drawings")
		(19 "Cmts.User" user "User.Comments")
		(21 "Eco1.User" user "User.Eco1")
		(23 "Eco2.User" user "User.Eco2")
		(25 "Edge.Cuts" user "Board Geometry/Outline")
		(27 "Margin" user)
		(31 "F.CrtYd" user "Package Geometry/Place Bound Top")
		(29 "B.CrtYd" user "Package Geometry/Place Bound Bottom")
		(35 "F.Fab" user "Ref Des/Assembly Top")
		(33 "B.Fab" user "Ref Des/Assembly Bottom")
	)
	(footprint ""
		(layer "B.Cu")
		(at 99.346766 -37.82314)
		(property "Reference" "C110"
			(at -42.196766 2.16789 0)
			(unlocked yes)
			(layer "B.SilkS")
			(effects
				(font
					(size 0.635 0.4064)
					(thickness 0.1524)
				)
				(justify mirror)
			)
		)
		(property "Value" "VAL*"
			(at 0 3.718306 0)
			(unlocked yes)
			(layer "B.Fab")
			(hide yes)
			(effects
				(font
					(size 0.7874 0.5842)
					(thickness 0.127)
				)
				(justify mirror)
			)
		)
		(property "Tolerance" "TOL*"
			(at 0 4.861306 0)
			(unlocked yes)
			(layer "Cmts.User")
			(hide yes)
			(effects
				(font
					(size 0.7874 0.5842)
					(thickness 0.127)
				)
				(justify mirror)
			)
		)
		(property "User Part Number" "PARTNUM*"
			(at 0 2.575306 0)
			(unlocked yes)
			(layer "Cmts.User")
			(hide yes)
			(effects
				(font
					(size 0.7874 0.5842)
					(thickness 0.127)
				)
				(justify mirror)
			)
		)
		(property "Device Type" "CAPACITOR-G105-0B104-CK,0.1UF,A"
			(at 0 1.432306 0)
			(unlocked yes)
			(layer "B.Fab")
			(hide yes)
			(effects
				(font
					(size 0.7874 0.5842)
					(thickness 0.127)
				)
				(justify mirror)
			)
		)
		(duplicate_pad_numbers_are_jumpers no)
		(fp_line
			(start -0.970026 -0.4699)
			(end -0.970026 0.4699)
			(stroke
				(width 0.1)
				(type default)
			)
			(layer "B.SilkS")
		)
		(fp_line
			(start -0.970026 0.4699)
			(end 0.970026 0.4699)
			(stroke
				(width 0.1)
				(type default)
			)
			(layer "B.SilkS")
		)
		(fp_line
			(start 0.970026 -0.4699)
			(end -0.970026 -0.4699)
			(stroke
				(width 0.1)
				(type default)
			)
			(layer "B.SilkS")
		)
		(fp_line
			(start 0.970026 0.4699)
			(end 0.970026 -0.4699)
			(stroke
				(width 0.1)
				(type default)
			)
			(layer "B.SilkS")
		)
		(fp_poly
			(pts
				(xy 0.970026 0.4699) (xy -0.970026 0.4699) (xy -0.970026 -0.4699) (xy 0.970026 -0.4699)
			)
			(stroke
				(width 0)
				(type default)
			)
			(fill no)
			(layer "B.CrtYd")
		)
		(fp_line
			(start -0.508 -0.3048)
			(end -0.508 0.3048)
			(stroke
				(width 0.1)
				(type default)
			)
			(layer "B.Fab")
		)
		(fp_line
			(start -0.508 0.3048)
			(end 0.508 0.3048)
			(stroke
				(width 0.1)
				(type default)
			)
			(layer "B.Fab")
		)
		(fp_line
			(start 0.508 -0.3048)
			(end -0.508 -0.3048)
			(stroke
				(width 0.1)
				(type default)
			)
			(layer "B.Fab")
		)
		(fp_line
			(start 0.508 0.3048)
			(end 0.508 -0.3048)
			(stroke
				(width 0.1)
				(type default)
			)
			(layer "B.Fab")
		)
		(pad "1" smd circle
			(at 0.500126 0 180)
			(size 0.635 0.635)
			(layers "B.Cu" "B.Mask" "B.Paste")
			(net "FPGA_MGTAVTT")
		)
		(pad "2" smd circle
			(at -0.500126 0 180)
			(size 0.635 0.635)
			(layers "B.Cu" "B.Mask" "B.Paste")
			(net "SG")
		)
	)
	(footprint ""
		(layer "B.Cu")
		(at 21.7932 -71.374 -90)
		(property "Reference" "R343"
			(at -0.254 1.13157 270)
			(unlocked yes)
			(layer "B.SilkS")
			(effects
				(font
					(size 0.7874 0.5842)
					(thickness 0.1524)
				)
				(justify mirror)
			)
		)
		(property "Value" "VAL*"
			(at -0.02032 2.13233 270)
			(unlocked yes)
			(layer "B.Fab")
			(hide yes)
			(effects
				(font
					(size 0.7874 0.5842)
					(thickness 0.1524)
				)
				(justify mirror)
			)
		)
		(property "Tolerance" "TOL*"
			(at -0.044704 3.05435 270)
			(unlocked yes)
			(layer "Cmts.User")
			(hide yes)
			(effects
				(font
					(size 0.7874 0.5842)
					(thickness 0.1524)
				)
				(justify mirror)
			)
		)
		(property "User Part Number" "PARTNUM*"
			(at -0.02032 4.024884 270)
			(unlocked yes)
			(layer "Cmts.User")
			(hide yes)
			(effects
				(font
					(size 0.7874 0.5842)
					(thickness 0.1524)
				)
				(justify mirror)
			)
		)
		(property "Device Type" "RESISTOR-G155-100R0-J0,0OHM,-"
			(at -0.008382 1.210564 270)
			(unlocked yes)
			(layer "B.Fab")
			(hide yes)
			(effects
				(font
					(size 0.7874 0.5842)
					(thickness 0.1524)
				)
				(justify mirror)
			)
		)
		(duplicate_pad_numbers_are_jumpers no)
		(fp_line
			(start -1.143 0.5588)
			(end -1.143 -0.5588)
			(stroke
				(width 0.1)
				(type default)
			)
			(layer "B.SilkS")
		)
		(fp_line
			(start 1.143 0.5588)
			(end -1.143 0.5588)
			(stroke
				(width 0.1)
				(type default)
			)
			(layer "B.SilkS")
		)
		(fp_line
			(start -1.143 -0.5588)
			(end 1.143 -0.5588)
			(stroke
				(width 0.1)
				(type default)
			)
			(layer "B.SilkS")
		)
		(fp_line
			(start 1.143 -0.5588)
			(end 1.143 0.5588)
			(stroke
				(width 0.1)
				(type default)
			)
			(layer "B.SilkS")
		)
		(fp_poly
			(pts
				(xy 1.143 0.5588) (xy -1.143 0.5588) (xy -1.143 -0.5588) (xy 1.143 -0.5588)
			)
			(stroke
				(width 0)
				(type default)
			)
			(fill no)
			(layer "B.CrtYd")
		)
		(fp_line
			(start -0.508 0.3048)
			(end -0.508 -0.3048)
			(stroke
				(width 0.1)
				(type default)
			)
			(layer "B.Fab")
		)
		(fp_line
			(start 0.508 0.3048)
			(end -0.508 0.3048)
			(stroke
				(width 0.1)
				(type default)
			)
			(layer "B.Fab")
		)
		(fp_line
			(start -0.508 -0.3048)
			(end 0.508 -0.3048)
			(stroke
				(width 0.1)
				(type default)
			)
			(layer "B.Fab")
		)
		(fp_line
			(start 0.508 -0.3048)
			(end 0.508 0.3048)
			(stroke
				(width 0.1)
				(type default)
			)
			(layer "B.Fab")
		)
		(pad "1" smd rect
			(at 0.5334 0 90)
			(size 0.7112 0.6096)
			(layers "B.Cu" "B.Mask" "B.Paste")
			(net "UNNAMED_8_ICP10100LGA10_I24_RES")
		)
		(pad "2" smd rect
			(at -0.5334 0 90)
			(size 0.7112 0.6096)
			(layers "B.Cu" "B.Mask" "B.Paste")
			(net "SG")
		)
		(zone
			(layer "B.Cu")
			(hatch none 0.5)
			(connect_pads
				(clearance 0)
			)
			(min_thickness 0.25)
			(keepout
				(tracks not_allowed)
				(vias allowed)
				(pads allowed)
				(copperpour not_allowed)
				(footprints allowed)
			)
			(placement
				(enabled no)
				(sheetname "")
			)
			(fill
				(thermal_gap 0.5)
				(thermal_bridge_width 0.5)
				(island_removal_mode 0)
			)
			(polygon
				(pts
					(xy 21.4884 -71.2978) (xy 22.098 -71.2978) (xy 22.098 -71.4502) (xy 21.4884 -71.4502)
				)
			)
		)
		(zone
			(layer "B.Cu")
			(hatch none 0.5)
			(connect_pads
				(clearance 0)
			)
			(min_thickness 0.25)
			(keepout
				(tracks allowed)
				(vias not_allowed)
				(pads allowed)
				(copperpour not_allowed)
				(footprints allowed)
			)
			(placement
				(enabled no)
				(sheetname "")
			)
			(fill
				(thermal_gap 0.5)
				(thermal_bridge_width 0.5)
				(island_removal_mode 0)
			)
			(polygon
				(pts
					(xy 21.4884 -71.2978) (xy 22.098 -71.2978) (xy 22.098 -71.4502) (xy 21.4884 -71.4502)
				)
			)
		)
	)
)
